FILE_TYPE = CONNECTIVITY;
{Allegro Design Entry HDL 16.6-p007 (v16-6-112F) 10/10/2012}
"PAGE_NUMBER" = 205;
0"NC";
1"PVSA_CPU0\g";
2"GND\g";
3"GND\g";
4"PVSA_CPU0\g";
5"GND\g";
6"VR_FET_SW_P12V_STBY_PVCCIN_CPU0\g";
7"GND\g";
8"PVSA_CPU0\g";
9"P5V_STBY\g";
10"GND\g";
11"GND\g";
12"GND\g";
13"GND\g";
14"GND\g";
15"VR_PVSA_CPU0_PHASE_SW"VOLTAGE"5";
16"VSENSE_PVSA_CPU0_P";
17"VR_PVSA_CPU0_PHASE"VOLTAGE"5";
18"VR_PVSA_CPU0_BOOT_R";
19"VR_PVSA_CPU0_BOOT";
20"VSENSE_PVSA_CPU0_SKT_VSEN";
21"VR_PVSA_CPU0_VCIN"VOLTAGE"5";
22"A_TSENSE_PVSA_CPU0";
23"UN$205$3D01R5F-GP$I68$2";
24"VR_PVSA_CPU0_PWM";
25"ISENSE_PVSA_CPU0_IMON";
26"VR_PVSA_CPU0_OCSET";
27"VR_PVSA_CPU0_BIREF1";
28"VSENSE_PVSA_CPU0_SKT_VRTN";
29"VSENSE_PVSA_CPU0_N";
30"NC_PVSA_CPU0_P31";
31"TP_PVSA_CPU0_GL_1";
32"TP_PVSA_CPU0_GL_0";
%"PVSA_CPU0"
"1","(-2000,1675)","0","mstr_symbols","I11";
;
HDL_POWER"PVSA_CPU0"
BODY_TYPE"PLUMBING"
CDS_LIB"mstr_symbols"
VOLTAGE"1.1V";
"G\NAC"1;
%"CAPP"
"1","(-2000,1300)","0","mstr_discrete","I12";
;
CDS_SEC"1"
CDS_LIB"mstr_discrete"
CDS_LOCATION"C6N1"
ROOM"PVSA_CPU0_DECAP_VR"
BOM_COST"PROC_VRD_VCCIN_CPU0"
SEC"1"
SEC_TYPE"3018"
MATERIAL"ALUM"
VOLTAGE"2.5V"
PACK_TYPE"3018"
TOLERANCE"20%"
VALUE"470UF"
LOCATION"C6N1"
PART_NUMBER"699013-049";
"B"
$PN"2"2;
"A"
$PN"1"1;
%"GND"
"1","(-2000,900)","0","mstr_symbols","I13";
;
ROOM"PVSA_CPU0_DECAP_VR"
BOM_COST"PROC_VRD_VCCIN_CPU0"
VOLTAGE"0"
BODY_TYPE"PLUMBING"
SIZE"1B"
CDS_LIB"mstr_symbols"
HDL_POWER"GND";
"A\NAC"2;
%"CAPP"
"1","(-2250,1300)","2","mstr_discrete","I14";
;
CDS_SEC"1"
CDS_LIB"mstr_discrete"
CDS_LOCATION"C6N4"
ROOM"PVSA_CPU0_DECAP_VR"
BOM_COST"PROC_VRD_VCCIN_CPU0"
SEC"1"
SEC_TYPE"3018"
MATERIAL"ALUM"
VOLTAGE"2.5V"
PACK_TYPE"3018"
TOLERANCE"20%"
LOCATION"C6N4"
VALUE"470UF"
PART_NUMBER"699013-049";
"B"
$PN"2"2;
"A"
$PN"1"1;
%"GND"
"1","(-2825,3075)","0","mstr_symbols","I15";
;
ROOM"PVSA_CPU0_PWR_VR"
BOM_COST"PROC_VRD_VCCIN_CPU0"
BODY_TYPE"PLUMBING"
SIZE"1B"
VOLTAGE"0"
CDS_LIB"mstr_symbols"
HDL_POWER"GND";
"A\NAC"3;
%"CAP"
"1","(-5775,4000)","0","mstr_discrete","I16";
;
CDS_SEC"1"
CDS_LIB"mstr_discrete"
SEC_TYPE"0402"
SEC"1"
CDS_LOCATION"C4C5"
ROOM"PVSA_CPU0_PWR_VR"
TOLERANCE"10%"
VALUE"0.22UF"
PART_NUMBER"A36096-155"
LOCATION"C4C5"
MATERIAL"X7R"
VOLTAGE"16V"
PACK_TYPE"0402";
"A"
$PN"1"9;
"B"
$PN"2"7;
%"CAP_A"
"1","(-5875,4000)","2","dev_discrete","I18";
;
CDS_LIB"dev_discrete"
ROOM"PVSA_CPU0_PWR_VR"
SEC"1"
SEC_TYPE"0402V"
CDS_SEC"1"
CDS_LOCATION"C4C4"
PART_NUMBER"D97712-004"
VOLTAGE"6.3V"
PACK_TYPE"0402V"
MATERIAL"X6S"
LOCATION"C4C4"
TOLERANCE"10%"
VALUE"1.0UF";
"B"
$PN"2"7;
"A"
$PN"1"9;
%"RES"
"1","(-6075,4525)","0","mstr_discrete","I19";
;
CDS_SEC"1"
CDS_LOCATION"R6N3"
CDS_LIB"mstr_discrete"
ROOM"PVSA_CPU0_PWR_VR"
SEC"1"
SEC_TYPE"0402"
VALUE"1.0"
WATTAGE"1/16W"
PART_NUMBER"G21796-090"
TOLERANCE"1%"
PACK_TYPE"0402"
LOCATION"R6N3"
MATERIAL"CHIP";
"B"
$PN"2"9;
"A"
$PN"1"21;
%"CAP"
"1","(-6350,3950)","0","mstr_discrete","I20";
;
CDS_SEC"1"
CDS_LOCATION"C4C6"
CDS_LIB"mstr_discrete"
SEC_TYPE"0402"
SEC"1"
ROOM"PVSA_CPU0_PWR_VR"
PACK_TYPE"0402"
MATERIAL"X6S"
VOLTAGE"16V"
TOLERANCE"10%"
PART_NUMBER"D97712-011"
VALUE"1.0UF"
LOCATION"C4C6";
"A"
$PN"1"21;
"B"
$PN"2"7;
%"PVSA_CPU0"
"1","(-4300,2650)","0","mstr_symbols","I23";
;
VOLTAGE"1.1V"
BOM_COST"PROC_VRD_VCCIN_CPU0"
CDS_LIB"mstr_symbols"
BODY_TYPE"PLUMBING"
HDL_POWER"PVSA_CPU0"
ROOM"PVSA_CPU0_VSENSE_VR";
"G\NAC"4;
%"RES"
"1","(-5100,2425)","0","mstr_discrete","I24";
;
CDS_SEC"1"
CDS_LOCATION"R4C5"
ROOM"PVSA_CPU0_VSENSE_VR"
BOM_COST"PROC_VRD_VCCIN_CPU0"
SEC"1"
SEC_TYPE"0402"
MATERIAL"CHIP"
CDS_LIB"mstr_discrete"
VALUE"100.0"
LOCATION"R4C5"
PART_NUMBER"G21796-017"
TOLERANCE"1%"
WATTAGE"1/16W"
PACK_TYPE"0402";
"B"
$PN"2"4;
"A"
$PN"1"16;
%"CAP"
"1","(-6400,3350)","2","mstr_discrete","I25";
;
CDS_SEC"1"
SEC"1"
SEC_TYPE"0402"
SPOF"TRUE"
ROOM"PVSA_CPU0_PWR_VR"
CDS_LOCATION"C4C8"
CDS_LIB"mstr_discrete"
VOLTAGE"16V"
LOCATION"C4C8"
TOLERANCE"10%"
MATERIAL"X7R"
PACK_TYPE"0402"
PART_NUMBER"A36096-104"
VALUE"0.220UF";
"A"
$PN"1"19;
"B"
$PN"2"17;
%"RES"
"1","(-5075,2025)","0","mstr_discrete","I26";
;
CDS_SEC"1"
CDS_LIB"mstr_discrete"
ROOM"PVSA_CPU0_VSENSE_VR"
CDS_LOCATION"R4C4"
BOM_COST"PROC_VRD_VCCIN_CPU0"
SEC_TYPE"0402"
SEC"1"
WATTAGE"1/16W"
PACK_TYPE"0402"
MATERIAL"CHIP"
TOLERANCE"5%"
PART_NUMBER"G21497-005"
LOCATION"R4C4"
VALUE"0.0";
"B"
$PN"2"20;
"A"
$PN"1"16;
%"GND"
"1","(-4250,1050)","0","mstr_symbols","I28";
;
BODY_TYPE"PLUMBING"
SIZE"1B"
ROOM"PVSA_CPU0_VSENSE_VR"
BOM_COST"PROC_VRD_VCCIN_CPU0"
VOLTAGE"0"
CDS_LIB"mstr_symbols"
HDL_POWER"GND";
"A\NAC"5;
%"RES"
"1","(-5075,1200)","0","mstr_discrete","I29";
;
CDS_SEC"1"
BOM_COST"PROC_VRD_VCCIN_CPU0"
CDS_LOCATION"R4C1"
ROOM"PVSA_CPU0_VSENSE_VR"
CDS_LIB"mstr_discrete"
MATERIAL"CHIP"
SEC"1"
SEC_TYPE"0402"
WATTAGE"1/16W"
TOLERANCE"1%"
PART_NUMBER"G21796-017"
LOCATION"R4C1"
VALUE"100.0"
PACK_TYPE"0402";
"B"
$PN"2"5;
"A"
$PN"1"29;
%"RES"
"1","(-5075,1575)","0","mstr_discrete","I30";
;
CDS_SEC"1"
BOM_COST"PROC_VRD_VCCIN_CPU0"
CDS_LOCATION"R4C2"
ROOM"PVSA_CPU0_VSENSE_VR"
CDS_LIB"mstr_discrete"
SEC"1"
SEC_TYPE"0402"
VALUE"0.0"
LOCATION"R4C2"
MATERIAL"CHIP"
TOLERANCE"5%"
PACK_TYPE"0402"
PART_NUMBER"G21497-005"
WATTAGE"1/16W";
"B"
$PN"2"28;
"A"
$PN"1"29;
%"CAP_A"
"1","(-6600,4000)","0","dev_discrete","I31";
;
CDS_LIB"dev_discrete"
ROOM"PVSA_CPU0_PWR_VR"
CDS_LOCATION"C4C10"
CDS_SEC"1"
SEC_TYPE"0402V"
SEC"1"
VALUE"0.1UF"
TOLERANCE"10%"
VOLTAGE"16V"
MATERIAL"X7R"
PART_NUMBER"A36096-030"
LOCATION"C4C10"
PACK_TYPE"0402V";
"B"
$PN"2"7;
"A"
$PN"1"6;
%"CAP"
"1","(-6850,3950)","0","mstr_discrete","I32";
;
CDS_SEC"1"
CDS_LOCATION"C4C9"
CDS_LIB"mstr_discrete"
ROOM"PVSA_CPU0_PWR_VR"
SEC"1"
SEC_TYPE"0402"
PACK_TYPE"0402"
MATERIAL"X6S"
TOLERANCE"10%"
LOCATION"C4C9"
VALUE"1.0UF"
VOLTAGE"16V"
PART_NUMBER"D97712-011";
"A"
$PN"1"6;
"B"
$PN"2"7;
%"CAP"
"1","(-7100,3975)","0","mstr_discrete","I33";
;
CDS_SEC"1"
CDS_LIB"mstr_discrete"
CDS_LOCATION"C6N2"
ROOM"PVSA_CPU0_PWR_VR"
SEC"1"
SEC_TYPE"0805"
PACK_TYPE"0805"
MATERIAL"X6S"
VOLTAGE"16V"
VALUE"10UF"
TOLERANCE"10%"
PART_NUMBER"C95333-007"
LOCATION"C6N2";
"A"
$PN"1"6;
"B"
$PN"2"7;
%"CAP"
"1","(-7325,3950)","0","mstr_discrete","I34";
;
CDS_SEC"1"
CDS_LIB"mstr_discrete"
CDS_LOCATION"C6N3"
ROOM"PVSA_CPU0_PWR_VR"
SEC"1"
SEC_TYPE"0805"
TOLERANCE"10%"
VOLTAGE"16V"
MATERIAL"X6S"
PACK_TYPE"0805"
VALUE"10UF"
PART_NUMBER"C95333-007"
LOCATION"C6N3";
"A"
$PN"1"6;
"B"
$PN"2"7;
%"CAP"
"1","(-7575,4000)","0","mstr_discrete","I35";
;
CDS_SEC"1"
CDS_LIB"mstr_discrete"
ROOM"PVSA_CPU0_PWR_VR"
SEC_TYPE"0805"
SEC"1"
CDS_LOCATION"C6N6"
TOLERANCE"10%"
VOLTAGE"16V"
MATERIAL"X6S"
PACK_TYPE"0805"
VALUE"10UF"
PART_NUMBER"C95333-007"
LOCATION"C6N6";
"A"
$PN"1"6;
"B"
$PN"2"7;
%"VCC_CORE"
"1","(-7575,4475)","0","mstr_symbols","I36";
;
CDS_LIB"mstr_symbols"
HDL_POWER"VR_FET_SW_P12V_STBY_PVCCIN_CPU0";
"A"6;
%"RES"
"2","(-5750,1825)","0","mstr_discrete","I37";
;
CDS_SEC"1"
CDS_LIB"mstr_discrete"
ROOM"PVSA_CPU0_VSENSE_VR"
CDS_LOCATION"R4C3"
BOM_COST"PROC_VRD_VCCIN_CPU0"
SEC_TYPE"0402"
SEC"1"
NO_XNET_CONNECTION"1"
TOLERANCE"1%"
WATTAGE"1/16W"
PACK_TYPE"0402"
VALUE"1.00K"
PART_NUMBER"G21796-026"
LOCATION"R4C3"
MATERIAL"EMPTY";
"A"
$PN"1"16;
"B"
$PN"2"29;
%"GND"
"1","(-7575,3550)","0","mstr_symbols","I39";
;
ROOM"PVSA_CPU0_PWR_VR"
BOM_COST"PROC_VRD_VCCIN_CPU0"
BODY_TYPE"PLUMBING"
SIZE"1B"
CDS_LIB"mstr_symbols"
VOLTAGE"0"
HDL_POWER"GND";
"A\NAC"7;
%"PVSA_CPU0"
"1","(-625,3525)","0","mstr_symbols","I4";
;
VOLTAGE"1.1V"
BODY_TYPE"PLUMBING"
CDS_LIB"mstr_symbols"
HDL_POWER"PVSA_CPU0";
"G\NAC"8;
%"P5V_STBY"
"1","(-4900,4650)","0","mstr_symbols","I42";
;
HDL_POWER"P5V_STBY"
VOLTAGE"5.0V"
BODY_TYPE"PLUMBING"
SIZE"1B"
CDS_LIB"mstr_symbols";
"G\NAC"9;
%"CAP_A"
"1","(-950,2875)","0","dev_discrete","I43";
;
CDS_LOCATION"C4C11"
CDS_LIB"dev_discrete"
CDS_SEC"1"
SEC_TYPE"0603V"
SEC"1"
MATERIAL"X6S"
TOLERANCE"20%"
VOLTAGE"4V"
PACK_TYPE"0603V"
VALUE"22.0UF"
PART_NUMBER"E15431-004"
LOCATION"C4C11";
"B"
$PN"2"10;
"A"
$PN"1"8;
%"RES"
"2","(-625,2875)","0","mstr_discrete","I45";
;
CDS_LOCATION"R6N4"
CDS_LIB"mstr_discrete"
$SEC"1"
CDS_SEC"1"
WATTAGE"1/16W"
MATERIAL"CHIP"
PACK_TYPE"0402"
TOLERANCE"1.0%"
VALUE"51.1"
PART_NUMBER"G21796-208"
LOCATION"R6N4";
"A"
$PN"1"8;
"B"
$PN"2"10;
%"IR354XX"
"1","(-3500,3725)","0","mstr_discrete","I46";
;
CDS_LIB"mstr_discrete"
CDS_LOCATION"EU4C1"
CDS_SEC"1"
$SEC"1"
PACK_TYPE"SM"
PART_NUMBER"H73684-001"
MATERIAL"IC"
LOCATION"EU4C1"
VALUE"IR35412";
"TOUT_FLT"
$PN"36"22;
"NC"
$PN"31"30;
"OCSET"
$PN"37"26;
"IOUT"
$PN"38"25;
"SW"
$PN"10"15;
"BOOST"
$PN"33"18;
"REFIN"
$PN"39"27;
"PWM"
$PN"34"24;
"PHASE"
$PN"32"17;
"VIN<0>"
$PN"25"6;
"VCC"
$PN"3"21;
"VIN<1>"
$PN"30"6;
"EN"
$PN"35"9;
"VDRV"
$PN"4"9;
"VOS"
$PN"1"8;
"LGND"
$PN"2"3;
"PGND<1>"
$PN"7"3;
"PGND<2>"
$PN"40"3;
"PGND<0>"
$PN"5"3;
"GL<0>"
$PN"6"32;
"GL<1>"
$PN"41"31;
%"CAP_A"
"1","(-1300,2875)","0","dev_discrete","I5";
;
CDS_LIB"dev_discrete"
CDS_LOCATION"C6N7"
CDS_SEC"1"
ROOM"PVSA_CPU0_PWR_VR"
BOM_COST"PROC_VRD_VCCIN_CPU0"
SEC_TYPE"0603V"
SEC"1"
MATERIAL"X6S"
VOLTAGE"4V"
LOCATION"C6N7"
VALUE"22.0UF"
TOLERANCE"20%"
PACK_TYPE"0603V"
PART_NUMBER"E15431-004";
"B"
$PN"2"10;
"A"
$PN"1"8;
%"GND"
"1","(-625,2525)","0","mstr_symbols","I6";
;
ROOM"PVSA_CPU0_PWR_VR"
BODY_TYPE"PLUMBING"
SIZE"1B"
CDS_LIB"mstr_symbols"
VOLTAGE"0"
BOM_COST"PROC_VRD_VCCIN_CPU0"
HDL_POWER"GND";
"A\NAC"10;
%"RES"
"2","(-1125,3900)","0","mstr_discrete","I62";
;
CDS_LOCATION"R4C13"
CDS_LIB"mstr_discrete"
CDS_SEC"1"
$SEC"1"
WATTAGE"1/16W"
PACK_TYPE"0402"
TOLERANCE"1%"
VALUE"68.1K"
PART_NUMBER"G21796-187"
LOCATION"R4C13"
MATERIAL"EMPTY";
"A"
$PN"1"26;
"B"
$PN"2"11;
%"GND"
"1","(-1125,3625)","0","mstr_symbols","I63";
;
ROOM"PVSA_CPU1_PWR_VR"
BODY_TYPE"PLUMBING"
SIZE"1B"
BOM_COST"PROC_VRD_VCCIN_CPU0"
CDS_LIB"mstr_symbols"
VOLTAGE"0"
HDL_POWER"GND";
"A\NAC"11;
%"SC2K2P50V3KX-GP"
"1","(-2225,3250)","0","w_hdl","I64";
;
CDS_SEC"1"
$SEC"1"
CDS_LOCATION"CT59"
CDS_LMAN_SYM_OUTLINE"-50,25,50,-25"
CDS_LIB"w_hdl"
PART_NUMBER"78.22224.2BL"
PACK_TYPE"SMD-BCG6"
LOCATION"CT59"
STATUS"NOPOP"
VALUE"SC2K2P50V3KX-GP";
"2"
$PN"2"23;
"1"
$PN"1"15;
%"CAP"
"1","(-2375,3750)","0","mstr_discrete","I65";
;
CDS_SEC"1"
$SEC"1"
CDS_LOCATION"CT58"
ROOM"VDDQ_KLM_PWR_VR"
CDS_LIB"mstr_discrete"
LOCATION"CT58"
VOLTAGE"50V"
VALUE"1000PF"
STATUS"NOPOP"
PART_NUMBER"A36096-046"
PACK_TYPE"0402LF"
TOLERANCE"10%"
MATERIAL"X7R";
"A"
$PN"1"22;
"B"
$PN"2"12;
%"GND"
"1","(-2375,3550)","0","mstr_symbols","I66";
;
ROOM"VDDQ_KLM_PWR_VR"
VOLTAGE"0"
BODY_TYPE"PLUMBING"
SIZE"1B"
HDL_POWER"GND"
CDS_LIB"mstr_symbols";
"A\NAC"12;
%"GND"
"1","(-2225,2750)","0","mstr_symbols","I67";
;
CDS_LIB"mstr_symbols"
HDL_POWER"GND"
SIZE"1B"
VOLTAGE"0"
BODY_TYPE"PLUMBING"
BOM_COST"PROC_VRD_VCCIN_CPU0"
ROOM"PVCCIN_CPU0_PWR_VR";
"A\NAC"13;
%"3D01R5F-GP"
"1","(-2225,2950)","4","w_hdl","I68";
;
CDS_SEC"1"
$SEC"1"
CDS_LOCATION"RT39"
CDS_LMAN_SYM_OUTLINE"-50,75,50,-75"
CDS_LIB"w_hdl"
PART_NUMBER"64.3R015.16L"
PACK_TYPE"SMD-RG5"
LOCATION"RT39"
STATUS"NOPOP"
VALUE"3D01R5F-GP";
"2"
$PN"2"23;
"1"
$PN"1"13;
%"CAP_A"
"1","(-4200,3225)","0","dev_discrete","I69";
;
CDS_SEC"1"
$SEC"1"
CDS_LOCATION"CT60"
CDS_LIB"dev_discrete"
ROOM"PVCCIN_CPU0_PWR_VR"
STATUS"NOPOP"
VALUE"0.1UF"
VOLTAGE"16V"
LOCATION"CT60"
MATERIAL"X7R"
PART_NUMBER"A36096-030"
PACK_TYPE"0402V"
TOLERANCE"10%";
"B"
$PN"2"14;
"A"
$PN"1"27;
%"INDUCTOR"
"1","(-1725,3425)","0","mstr_discrete","I7";
;
CDS_SEC"1"
ROOM"PVSA_CPU0_PWR_VR"
CDS_LOCATION"L4C2"
CDS_LIB"mstr_discrete"
SEC"1"
SEC_TYPE"SM"
VALUE"0.3UH"
LOCATION"L4C2"
PART_NUMBER"D92183-036"
MATERIAL"IND"
PACK_TYPE"SM";
"INA\NAC"
$PN"1"15;
"INB\NAC"
$PN"2"8;
%"GND"
"1","(-4200,2975)","0","mstr_symbols","I70";
;
CDS_LIB"mstr_symbols"
HDL_POWER"GND"
VOLTAGE"0"
SIZE"1B"
BOM_COST"PROC_VRD_VCCIN_CPU0"
ROOM"PVCCIN_CPU0_PWR_VR"
BODY_TYPE"PLUMBING";
"A\NAC"14;
%"RES"
"1","(-5600,3500)","0","mstr_discrete","I72";
;
CDS_SEC"1"
$SEC"1"
CDS_LOCATION"RT40"
CDS_LIB"mstr_discrete"
ROOM"BMC_DEBUG_HEADER"
BOM_COST"DEBUG"
LOCATION"RT40"
PART_NUMBER"G21497-005"
VALUE"0.0"
TOLERANCE"5%"
MATERIAL"CHIP"
PACK_TYPE"0402"
WATTAGE"1/16W";
"B"
$PN"2"18;
"A"
$PN"1"19;
END.
